# BASEBOARD_FAB2 (Tioga Pass) — schematic netlist excerpt (pin names and nets, part order shuffled) for the footprints in the layout excerpt that follows; sources: Cadence DE-HDL packaged netlist, KiCad conversion of Wiwynn_Tioga_Pass_MB.brd

J9U2  SCONN288_H44441003  SCONN  pkg PIP  page 82
  \12v\(1)  = P12V_NVDIMM_GHJ
  VSS(93)  = GND
  DQ(4)  = M_J_DQ<4>
  VSS(92)  = GND
  DQ(0)  = M_J_DQ<0>
  VSS(91)  = GND
  DQS9P  = M_J_DQS_DP<9>
  DQS9N  = M_J_DQS_DN<9>
  VSS(90)  = GND
  DQ(6)  = M_J_DQ<6>
  VSS(89)  = GND
  DQ(2)  = M_J_DQ<2>
  VSS(88)  = GND
  DQ(12)  = M_J_DQ<12>
  VSS(87)  = GND
  DQ(8)  = M_J_DQ<8>
  VSS(86)  = GND
  DQS10P  = M_J_DQS_DP<10>
  DQS10N  = M_J_DQS_DN<10>
  VSS(85)  = GND
  DQ(14)  = M_J_DQ<14>
  VSS(84)  = GND
  DQ(10)  = M_J_DQ<10>
  VSS(83)  = GND
  DQ(20)  = M_J_DQ<20>
  VSS(82)  = GND
  DQ(16)  = M_J_DQ<16>
  VSS(81)  = GND
  DQS11P  = M_J_DQS_DP<11>
  DQS11N  = M_J_DQS_DN<11>
  VSS(80)  = GND
  DQ(22)  = M_J_DQ<22>
  VSS(79)  = GND
  DQ(18)  = M_J_DQ<18>
  VSS(78)  = GND
  DQ(28)  = M_J_DQ<28>
  VSS(77)  = GND
  DQ(24)  = M_J_DQ<24>
  VSS(76)  = GND
  DQS12P  = M_J_DQS_DP<12>
  DQS12N  = M_J_DQS_DN<12>
  VSS(75)  = GND
  DQ(30)  = M_J_DQ<30>
  VSS(74)  = GND
  DQ(26)  = M_J_DQ<26>
  VSS(73)  = GND
  CB(4)  = M_J_ECC<4>
  VSS(72)  = GND
  CB(0)  = M_J_ECC<0>
  VSS(71)  = GND
  DQS17P  = M_J_DQS_DP<17>
  DQS17N  = M_J_DQS_DN<17>
  VSS(70)  = GND
  CB(6)  = M_J_ECC<6>
  VSS(69)  = GND
  CB(2)  = M_J_ECC<2>
  VSS(68)  = GND
  RESET_N  = M_GHJ_RST_N
  VDD(25)  = PVDDQ_GHJ
  CKE(0)  = M_J_CKE<2>
  VDD(24)  = PVDDQ_GHJ
  ACT_N  = M_J_ACT_N
  BG(0)  = M_J_BG<0>
  VDD(23)  = PVDDQ_GHJ
  A12  = M_J_MA<12>
  A9  = M_J_MA<9>
  VDD(22)  = PVDDQ_GHJ
  A8  = M_J_MA<8>
  A6  = M_J_MA<6>
  VDD(21)  = PVDDQ_GHJ
  A3  = M_J_MA<3>
  A1  = M_J_MA<1>
  VDD(20)  = PVDDQ_GHJ
  CK0P  = M_J_CLK_DP<2>
  CK0N  = M_J_CLK_DN<2>
  VDD(19)  = PVDDQ_GHJ
  VTT(1)  = PVTT_GHJ
  EVENT_N  = FM_DIMM_EVENT_COD_N
  A0  = M_J_MA<0>
  VDD(18)  = PVDDQ_GHJ
  BA(0)  = M_J_BA<0>
  A16_RAS_N  = M_J_MA<16>
  VDD(17)  = PVDDQ_GHJ
  S0_N  = M_J_CS_N<4>
  VDD(16)  = PVDDQ_GHJ
  A15_CAS_N  = M_J_MA<15>
  ODT(0)  = M_J_ODT<2>
  VDD(15)  = PVDDQ_GHJ
  S1_N  = M_J_CS_N<5>
  VDD(14)  = PVDDQ_GHJ
  ODT(1)  = M_J_ODT<3>
  VDD(13)  = PVDDQ_GHJ
  S2_N_C(0)  = M_J_CS_N<6>
  VSS(67)  = GND
  DQ(36)  = M_J_DQ<36>
  VSS(66)  = GND
  DQ(32)  = M_J_DQ<32>
  VSS(65)  = GND
  DQS13P  = M_J_DQS_DP<13>
  DQS13N  = M_J_DQS_DN<13>
  VSS(64)  = GND
  DQ(38)  = M_J_DQ<38>
  VSS(63)  = GND
  DQ(34)  = M_J_DQ<34>
  VSS(62)  = GND
  DQ(44)  = M_J_DQ<44>
  VSS(61)  = GND
  DQ(40)  = M_J_DQ<40>
  VSS(60)  = GND
  DQS14P  = M_J_DQS_DP<14>
  DQS14N  = M_J_DQS_DN<14>
  VSS(59)  = GND
  DQ(46)  = M_J_DQ<46>
  VSS(58)  = GND
  DQ(42)  = M_J_DQ<42>
  VSS(57)  = GND
  DQ(52)  = M_J_DQ<52>
  VSS(56)  = GND
  DQ(48)  = M_J_DQ<48>
  VSS(55)  = GND
  DQS15P  = M_J_DQS_DP<15>
  DQS15N  = M_J_DQS_DN<15>
  VSS(54)  = GND
  DQ(54)  = M_J_DQ<54>
  VSS(53)  = GND
  DQ(50)  = M_J_DQ<50>
  VSS(52)  = GND
  DQ(60)  = M_J_DQ<60>
  VSS(51)  = GND
  DQ(56)  = M_J_DQ<56>
  VSS(50)  = GND
  DQS16P  = M_J_DQS_DP<16>
  DQS16N  = M_J_DQS_DN<16>
  VSS(49)  = GND
  DQ(62)  = M_J_DQ<62>
  VSS(48)  = GND
  DQ(58)  = M_J_DQ<58>
  VSS(47)  = GND
  SA(0)  = PVPP_GHJ
  SA(1)  = GND
  SCL  = SMB_DDR_GHJ_VPP_SCL
  VPP(4)  = PVPP_GHJ
  VPP(3)  = PVPP_GHJ
  RFU(2)  = TP_CH_J_DIMM_J1_RFU_2
  \12v\(0)  = P12V_NVDIMM_GHJ
  VREFCA  = M_J_VREF
  VSS(46)  = GND
  DQ(5)  = M_J_DQ<5>
  VSS(45)  = GND
  DQ(1)  = M_J_DQ<1>
  VSS(44)  = GND
  DQS0N  = M_J_DQS_DN<0>
  DQS0P  = M_J_DQS_DP<0>
  VSS(43)  = GND
  DQ(7)  = M_J_DQ<7>
  VSS(42)  = GND
  DQ(3)  = M_J_DQ<3>
  VSS(41)  = GND
  DQ(13)  = M_J_DQ<13>
  VSS(40)  = GND
  DQ(9)  = M_J_DQ<9>
  VSS(39)  = GND
  DQS1N  = M_J_DQS_DN<1>
  DQS1P  = M_J_DQS_DP<1>
  VSS(38)  = GND
  DQ(15)  = M_J_DQ<15>
  VSS(37)  = GND
  DQ(11)  = M_J_DQ<11>
  VSS(36)  = GND
  DQ(21)  = M_J_DQ<21>
  VSS(35)  = GND
  DQ(17)  = M_J_DQ<17>
  VSS(34)  = GND
  DQS2N  = M_J_DQS_DN<2>
  DQS2P  = M_J_DQS_DP<2>
  VSS(33)  = GND
  DQ(23)  = M_J_DQ<23>
  VSS(32)  = GND
  DQ(19)  = M_J_DQ<19>
  VSS(31)  = GND
  DQ(29)  = M_J_DQ<29>
  VSS(30)  = GND
  DQ(25)  = M_J_DQ<25>
  VSS(29)  = GND
  DQS3N  = M_J_DQS_DN<3>
  DQS3P  = M_J_DQS_DP<3>
  VSS(28)  = GND
  DQ(31)  = M_J_DQ<31>
  VSS(27)  = GND
  DQ(27)  = M_J_DQ<27>
  VSS(26)  = GND
  CB(5)  = M_J_ECC<5>
  VSS(25)  = GND
  CB(1)  = M_J_ECC<1>
  VSS(24)  = GND
  DQS8N  = M_J_DQS_DN<8>
  DQS8P  = M_J_DQS_DP<8>
  VSS(23)  = GND
  CB(7)  = M_J_ECC<7>
  VSS(22)  = GND
  CB(3)  = M_J_ECC<3>
  VSS(21)  = GND
  CKE(1)  = M_J_CKE<3>
  VDD(12)  = PVDDQ_GHJ
  RFU(0)  = TP_CH_J_DIMM_J1_RFU_0
  VDD(11)  = PVDDQ_GHJ
  BG(1)  = M_J_BG<1>
  ALERT_N  = M_J_ALERT_N
  VDD(10)  = PVDDQ_GHJ
  A11  = M_J_MA<11>
  A7  = M_J_MA<7>
  VDD(9)  = PVDDQ_GHJ
  A5  = M_J_MA<5>
  A4  = M_J_MA<4>
  VDD(8)  = PVDDQ_GHJ
  A2  = M_J_MA<2>
  VDD(7)  = PVDDQ_GHJ
  CK1P  = M_J_CLK_DP<3>
  CK1N  = M_J_CLK_DN<3>
  VDD(6)  = PVDDQ_GHJ
  VTT(0)  = PVTT_GHJ
  PAR  = M_J_PAR
  VDD(5)  = PVDDQ_GHJ
  BA(1)  = M_J_BA<1>
  A10  = M_J_MA<10>
  VDD(4)  = PVDDQ_GHJ
  RFU(1)  = TP_CH_J_DIMM_J1_RFU_1
  A14_WE_N  = M_J_MA<14>
  VDD(3)  = PVDDQ_GHJ
  SAVE_N_NC  = FM_ADR_COMPLETE_GHJ_N
  VDD(2)  = PVDDQ_GHJ
  A13  = M_J_MA<13>
  VDD(1)  = PVDDQ_GHJ
  A17  = M_J_MA<17>
  C(2)  = M_J_C<2>
  VDD(0)  = PVDDQ_GHJ
  S3_N_C(1)  = M_J_CS_N<7>
  SA(2)  = PVPP_GHJ
  VSS(20)  = GND
  DQ(37)  = M_J_DQ<37>
  VSS(19)  = GND
  DQ(33)  = M_J_DQ<33>
  VSS(18)  = GND
  DQS4N  = M_J_DQS_DN<4>
  DQS4P  = M_J_DQS_DP<4>
  VSS(17)  = GND
  DQ(39)  = M_J_DQ<39>
  VSS(16)  = GND
  DQ(35)  = M_J_DQ<35>
  VSS(15)  = GND
  DQ(45)  = M_J_DQ<45>
  VSS(14)  = GND
  DQ(41)  = M_J_DQ<41>
  VSS(13)  = GND
  DQS5N  = M_J_DQS_DN<5>
  DQS5P  = M_J_DQS_DP<5>
  VSS(12)  = GND
  DQ(47)  = M_J_DQ<47>
  VSS(11)  = GND
  DQ(43)  = M_J_DQ<43>
  VSS(10)  = GND
  DQ(53)  = M_J_DQ<53>
  VSS(9)  = GND
  DQ(49)  = M_J_DQ<49>
  VSS(8)  = GND
  DQS6N  = M_J_DQS_DN<6>
  DQS6P  = M_J_DQS_DP<6>
  VSS(7)  = GND
  DQ(55)  = M_J_DQ<55>
  VSS(6)  = GND
  DQ(51)  = M_J_DQ<51>
  VSS(5)  = GND
  DQ(61)  = M_J_DQ<61>
  VSS(4)  = GND
  DQ(57)  = M_J_DQ<57>
  VSS(3)  = GND
  DQS7N  = M_J_DQS_DN<7>
  DQS7P  = M_J_DQS_DP<7>
  VSS(2)  = GND
  DQ(63)  = M_J_DQ<63>
  VSS(1)  = GND
  DQ(59)  = M_J_DQ<59>
  VSS(0)  = GND
  VDDSPD  = PVPP_GHJ
  SDA  = SMB_DDR_GHJ_VPP_SDA
  VPP(1)  = PVPP_GHJ
  VPP(0)  = PVPP_GHJ
  VPP(2)  = PVPP_GHJ

(kicad_pcb
	(version 20260206)
	(generator "pcbnew")
	(generator_version "10.0")
	(general
		(thickness 1.6)
		(legacy_teardrops no)
	)
	(paper "A4")
	(title_block
		(title "Wiwynn_Tioga_Pass_MB.brd")
		(comment 1 "Tioga Pass / footprint 4543 of 4770 (J9U2), pads 101-151 of 291")
	)
	(layers
		(0 "F.Cu" signal "TOP")
		(4 "In1.Cu" signal "L2GND")
		(6 "In2.Cu" signal "L3")
		(8 "In3.Cu" signal "L4GND")
		(10 "In4.Cu" signal "L5")
		(12 "In5.Cu" signal "L6GND")
		(14 "In6.Cu" signal "L7VCC")
		(16 "In7.Cu" signal "L8VCC")
		(18 "In8.Cu" signal "L9GND")
		(20 "In9.Cu" signal "L10")
		(22 "In10.Cu" signal "L11GND")
		(24 "In11.Cu" signal "L12")
		(26 "In12.Cu" signal "L13GND")
		(2 "B.Cu" signal "BOTTOM")
		(9 "F.Adhes" user "F.Adhesive")
		(11 "B.Adhes" user "B.Adhesive")
		(13 "F.Paste" user "Package Geometry/Pastemask Top")
		(15 "B.Paste" user "Package Geometry/Pastemask Bottom")
		(5 "F.SilkS" user "Ref Des/Silkscreen Top")
		(7 "B.SilkS" user "Ref Des/Silkscreen Bottom")
		(1 "F.Mask" user "Board Geometry/Soldermask Top")
		(3 "B.Mask" user "Board Geometry/Soldermask Bottom")
		(17 "Dwgs.User" user "User.Drawings")
		(19 "Cmts.User" user "User.Comments")
		(21 "Eco1.User" user "User.Eco1")
		(23 "Eco2.User" user "User.Eco2")
		(25 "Edge.Cuts" user "Board Geometry/Outline")
		(27 "Margin" user)
		(31 "F.CrtYd" user "Package Geometry/Place Bound Top")
		(29 "B.CrtYd" user "Package Geometry/Place Bound Bottom")
		(35 "F.Fab" user "Ref Des/Assembly Top")
		(33 "B.Fab" user "Ref Des/Assembly Bottom")
	)
	(footprint ""
		(layer "B.Cu")
		(at 29.699458 -5.621782 90)
		(property "Reference" "J9U2"
			(at 2.098548 38.118542 0)
			(unlocked yes)
			(layer "B.SilkS")
			(effects
				(font
					(size 0.7874 0.5842)
					(thickness 0.1524)
				)
				(justify left mirror)
			)
		)
		(property "Value" ""
			(at 0 0 90)
			(layer "B.Fab")
			(effects
				(font
					(size 1.27 1.27)
				)
				(justify mirror)
			)
		)
		(duplicate_pad_numbers_are_jumpers no)
		(pad "98" smd rect
			(at 0 87.54999 270)
			(size 1.8034 0.508)
			(layers "B.Cu" "B.Mask" "B.Paste")
			(net "GND")
		)
		(pad "99" smd rect
			(at 0 88.399874 270)
			(size 1.8034 0.508)
			(layers "B.Cu" "B.Mask" "B.Paste")
			(net "M_J_DQS_DP<13>")
		)
		(pad "100" smd rect
			(at 0 89.250012 270)
			(size 1.8034 0.508)
			(layers "B.Cu" "B.Mask" "B.Paste")
			(net "M_J_DQS_DN<13>")
		)
		(pad "101" smd rect
			(at 0 90.099896 270)
			(size 1.8034 0.508)
			(layers "B.Cu" "B.Mask" "B.Paste")
			(net "GND")
		)
		(pad "102" smd rect
			(at 0 90.950034 270)
			(size 1.8034 0.508)
			(layers "B.Cu" "B.Mask" "B.Paste")
			(net "M_J_DQ<38>")
		)
		(pad "103" smd rect
			(at 0 91.799918 270)
			(size 1.8034 0.508)
			(layers "B.Cu" "B.Mask" "B.Paste")
			(net "GND")
		)
		(pad "104" smd rect
			(at 0 92.650056 270)
			(size 1.8034 0.508)
			(layers "B.Cu" "B.Mask" "B.Paste")
			(net "M_J_DQ<34>")
		)
		(pad "105" smd rect
			(at 0 93.49994 270)
			(size 1.8034 0.508)
			(layers "B.Cu" "B.Mask" "B.Paste")
			(net "GND")
		)
		(pad "106" smd rect
			(at 0 94.350078 270)
			(size 1.8034 0.508)
			(layers "B.Cu" "B.Mask" "B.Paste")
			(net "M_J_DQ<44>")
		)
		(pad "107" smd rect
			(at 0 95.199962 270)
			(size 1.8034 0.508)
			(layers "B.Cu" "B.Mask" "B.Paste")
			(net "GND")
		)
		(pad "108" smd rect
			(at 0 96.0501 270)
			(size 1.8034 0.508)
			(layers "B.Cu" "B.Mask" "B.Paste")
			(net "M_J_DQ<40>")
		)
		(pad "109" smd rect
			(at 0 96.899984 270)
			(size 1.8034 0.508)
			(layers "B.Cu" "B.Mask" "B.Paste")
			(net "GND")
		)
		(pad "110" smd rect
			(at 0 97.750122 270)
			(size 1.8034 0.508)
			(layers "B.Cu" "B.Mask" "B.Paste")
			(net "M_J_DQS_DP<14>")
		)
		(pad "111" smd rect
			(at 0 98.600006 270)
			(size 1.8034 0.508)
			(layers "B.Cu" "B.Mask" "B.Paste")
			(net "M_J_DQS_DN<14>")
		)
		(pad "112" smd rect
			(at 0 99.44989 270)
			(size 1.8034 0.508)
			(layers "B.Cu" "B.Mask" "B.Paste")
			(net "GND")
		)
		(pad "113" smd rect
			(at 0 100.300028 270)
			(size 1.8034 0.508)
			(layers "B.Cu" "B.Mask" "B.Paste")
			(net "M_J_DQ<46>")
		)
		(pad "114" smd rect
			(at 0 101.149912 270)
			(size 1.8034 0.508)
			(layers "B.Cu" "B.Mask" "B.Paste")
			(net "GND")
		)
		(pad "115" smd rect
			(at 0 102.00005 270)
			(size 1.8034 0.508)
			(layers "B.Cu" "B.Mask" "B.Paste")
			(net "M_J_DQ<42>")
		)
		(pad "116" smd rect
			(at 0 102.849934 270)
			(size 1.8034 0.508)
			(layers "B.Cu" "B.Mask" "B.Paste")
			(net "GND")
		)
		(pad "117" smd rect
			(at 0 103.700072 270)
			(size 1.8034 0.508)
			(layers "B.Cu" "B.Mask" "B.Paste")
			(net "M_J_DQ<52>")
		)
		(pad "118" smd rect
			(at 0 104.549956 270)
			(size 1.8034 0.508)
			(layers "B.Cu" "B.Mask" "B.Paste")
			(net "GND")
		)
		(pad "119" smd rect
			(at 0 105.400094 270)
			(size 1.8034 0.508)
			(layers "B.Cu" "B.Mask" "B.Paste")
			(net "M_J_DQ<48>")
		)
		(pad "120" smd rect
			(at 0 106.249978 270)
			(size 1.8034 0.508)
			(layers "B.Cu" "B.Mask" "B.Paste")
			(net "GND")
		)
		(pad "121" smd rect
			(at 0 107.100116 270)
			(size 1.8034 0.508)
			(layers "B.Cu" "B.Mask" "B.Paste")
			(net "M_J_DQS_DP<15>")
		)
		(pad "122" smd rect
			(at 0 107.95 270)
			(size 1.8034 0.508)
			(layers "B.Cu" "B.Mask" "B.Paste")
			(net "M_J_DQS_DN<15>")
		)
		(pad "123" smd rect
			(at 0 108.799884 270)
			(size 1.8034 0.508)
			(layers "B.Cu" "B.Mask" "B.Paste")
			(net "GND")
		)
		(pad "124" smd rect
			(at 0 109.650022 270)
			(size 1.8034 0.508)
			(layers "B.Cu" "B.Mask" "B.Paste")
			(net "M_J_DQ<54>")
		)
		(pad "125" smd rect
			(at 0 110.499906 270)
			(size 1.8034 0.508)
			(layers "B.Cu" "B.Mask" "B.Paste")
			(net "GND")
		)
		(pad "126" smd rect
			(at 0 111.350044 270)
			(size 1.8034 0.508)
			(layers "B.Cu" "B.Mask" "B.Paste")
			(net "M_J_DQ<50>")
		)
		(pad "127" smd rect
			(at 0 112.199928 270)
			(size 1.8034 0.508)
			(layers "B.Cu" "B.Mask" "B.Paste")
			(net "GND")
		)
		(pad "128" smd rect
			(at 0 113.050066 270)
			(size 1.8034 0.508)
			(layers "B.Cu" "B.Mask" "B.Paste")
			(net "M_J_DQ<60>")
		)
		(pad "129" smd rect
			(at 0 113.89995 270)
			(size 1.8034 0.508)
			(layers "B.Cu" "B.Mask" "B.Paste")
			(net "GND")
		)
		(pad "130" smd rect
			(at 0 114.750088 270)
			(size 1.8034 0.508)
			(layers "B.Cu" "B.Mask" "B.Paste")
			(net "M_J_DQ<56>")
		)
		(pad "131" smd rect
			(at 0 115.599972 270)
			(size 1.8034 0.508)
			(layers "B.Cu" "B.Mask" "B.Paste")
			(net "GND")
		)
		(pad "132" smd rect
			(at 0 116.45011 270)
			(size 1.8034 0.508)
			(layers "B.Cu" "B.Mask" "B.Paste")
			(net "M_J_DQS_DP<16>")
		)
		(pad "133" smd rect
			(at 0 117.299994 270)
			(size 1.8034 0.508)
			(layers "B.Cu" "B.Mask" "B.Paste")
			(net "M_J_DQS_DN<16>")
		)
		(pad "134" smd rect
			(at 0 118.149878 270)
			(size 1.8034 0.508)
			(layers "B.Cu" "B.Mask" "B.Paste")
			(net "GND")
		)
		(pad "135" smd rect
			(at 0 119.000016 270)
			(size 1.8034 0.508)
			(layers "B.Cu" "B.Mask" "B.Paste")
			(net "M_J_DQ<62>")
		)
		(pad "136" smd rect
			(at 0 119.8499 270)
			(size 1.8034 0.508)
			(layers "B.Cu" "B.Mask" "B.Paste")
			(net "GND")
		)
		(pad "137" smd rect
			(at 0 120.700038 270)
			(size 1.8034 0.508)
			(layers "B.Cu" "B.Mask" "B.Paste")
			(net "M_J_DQ<58>")
		)
		(pad "138" smd rect
			(at 0 121.549922 270)
			(size 1.8034 0.508)
			(layers "B.Cu" "B.Mask" "B.Paste")
			(net "GND")
		)
		(pad "139" smd rect
			(at 0 122.40006 270)
			(size 1.8034 0.508)
			(layers "B.Cu" "B.Mask" "B.Paste")
			(net "PVPP_GHJ")
		)
		(pad "140" smd rect
			(at 0 123.249944 270)
			(size 1.8034 0.508)
			(layers "B.Cu" "B.Mask" "B.Paste")
			(net "GND")
		)
		(pad "141" smd rect
			(at 0 124.100082 270)
			(size 1.8034 0.508)
			(layers "B.Cu" "B.Mask" "B.Paste")
			(net "SMB_DDR_GHJ_VPP_SCL")
		)
		(pad "142" smd rect
			(at 0 124.949966 270)
			(size 1.8034 0.508)
			(layers "B.Cu" "B.Mask" "B.Paste")
			(net "PVPP_GHJ")
		)
		(pad "143" smd rect
			(at 0 125.800104 270)
			(size 1.8034 0.508)
			(layers "B.Cu" "B.Mask" "B.Paste")
			(net "PVPP_GHJ")
		)
		(pad "144" smd rect
			(at 0 126.649988 270)
			(size 1.8034 0.508)
			(layers "B.Cu" "B.Mask" "B.Paste")
			(net "TP_CH_J_DIMM_J1_RFU_2")
		)
		(pad "145" smd rect
			(at -4.59994 0 270)
			(size 1.8034 0.508)
			(layers "B.Cu" "B.Mask" "B.Paste")
			(net "P12V_NVDIMM_GHJ")
		)
		(pad "146" smd rect
			(at -4.59994 0.849884 270)
			(size 1.8034 0.508)
			(layers "B.Cu" "B.Mask" "B.Paste")
			(net "M_J_VREF")
		)
		(pad "147" smd rect
			(at -4.59994 1.700022 270)
			(size 1.8034 0.508)
			(layers "B.Cu" "B.Mask" "B.Paste")
			(net "GND")
		)
		(pad "148" smd rect
			(at -4.59994 2.549906 270)
			(size 1.8034 0.508)
			(layers "B.Cu" "B.Mask" "B.Paste")
			(net "M_J_DQ<5>")
		)
	)
)
